(kicad_pcb
	(version 20260206)
	(generator "pcbnew")
	(generator_version "10.0")
	(general
		(thickness 1.6)
		(legacy_teardrops no)
	)
	(paper "A4")
	(title_block
		(title "01162023_DA0F0TEBIF0_F0T_Expander_BD_F_brd_V02_OCP.brd")
		(comment 1 "Grand Teton / footprints 8805-8811 of 9728")
	)
	(layers
		(0 "F.Cu" signal "TOP")
		(4 "In1.Cu" signal "GND")
		(6 "In2.Cu" signal "VCC")
		(8 "In3.Cu" signal "VCC1")
		(10 "In4.Cu" signal "GND1")
		(12 "In5.Cu" signal "IN1")
		(14 "In6.Cu" signal "GND2")
		(16 "In7.Cu" signal "IN2")
		(18 "In8.Cu" signal "GND3")
		(20 "In9.Cu" signal "IN3")
		(22 "In10.Cu" signal "GND4")
		(24 "In11.Cu" signal "IN4")
		(26 "In12.Cu" signal "GND5")
		(28 "In13.Cu" signal "IN5")
		(30 "In14.Cu" signal "GND6")
		(32 "In15.Cu" signal "IN6")
		(34 "In16.Cu" signal "GND7")
		(2 "B.Cu" signal "BOTTOM")
		(9 "F.Adhes" user "F.Adhesive")
		(11 "B.Adhes" user "B.Adhesive")
		(13 "F.Paste" user "Package Geometry/Pastemask Top")
		(15 "B.Paste" user "Package Geometry/Pastemask Bottom")
		(5 "F.SilkS" user "Ref Des/Silkscreen Top")
		(7 "B.SilkS" user "Ref Des/Silkscreen Bottom")
		(1 "F.Mask" user "Board Geometry/Soldermask Top")
		(3 "B.Mask" user "Board Geometry/Soldermask Bottom")
		(17 "Dwgs.User" user "User.Drawings")
		(19 "Cmts.User" user "User.Comments")
		(21 "Eco1.User" user "User.Eco1")
		(23 "Eco2.User" user "User.Eco2")
		(25 "Edge.Cuts" user "Board Geometry/Outline")
		(27 "Margin" user)
		(31 "F.CrtYd" user "Package Geometry/Place Bound Top")
		(29 "B.CrtYd" user "Package Geometry/Place Bound Bottom")
		(35 "F.Fab" user "Ref Des/Assembly Top")
		(33 "B.Fab" user "Ref Des/Assembly Bottom")
	)
	(footprint ""
		(layer "B.Cu")
		(at 134.798816 -211.080858 180)
		(property "Reference" "R982"
			(at 0 0 0)
			(layer "B.SilkS")
			(hide yes)
			(effects
				(font
					(size 1.27 1.27)
				)
				(justify mirror)
			)
		)
		(property "Value" ""
			(at 0 0 0)
			(layer "B.Fab")
			(effects
				(font
					(size 1.27 1.27)
				)
				(justify mirror)
			)
		)
		(duplicate_pad_numbers_are_jumpers no)
		(fp_line
			(start 0.7874 0.4064)
			(end 0.7874 -0.4064)
			(stroke
				(width 0.1524)
				(type default)
			)
			(layer "B.SilkS")
		)
		(fp_line
			(start 0.7874 -0.4064)
			(end -0.7874 -0.4064)
			(stroke
				(width 0.1524)
				(type default)
			)
			(layer "B.SilkS")
		)
		(fp_line
			(start -0.7874 0.4064)
			(end 0.7874 0.4064)
			(stroke
				(width 0.1524)
				(type default)
			)
			(layer "B.SilkS")
		)
		(fp_line
			(start -0.7874 -0.4064)
			(end -0.7874 0.4064)
			(stroke
				(width 0.1524)
				(type default)
			)
			(layer "B.SilkS")
		)
		(fp_line
			(start 0.67945 0.3048)
			(end 0.67945 -0.305054)
			(stroke
				(width 0.1)
				(type default)
			)
			(layer "B.Fab")
		)
		(fp_line
			(start 0.67945 -0.305054)
			(end 0.12065 -0.305054)
			(stroke
				(width 0.1)
				(type default)
			)
			(layer "B.Fab")
		)
		(fp_line
			(start 0.12065 0.3048)
			(end 0.67945 0.3048)
			(stroke
				(width 0.1)
				(type default)
			)
			(layer "B.Fab")
		)
		(fp_line
			(start 0.12065 0.2794)
			(end 0.12065 0.3048)
			(stroke
				(width 0.1)
				(type default)
			)
			(layer "B.Fab")
		)
		(fp_line
			(start 0.12065 -0.2794)
			(end -0.12065 -0.2794)
			(stroke
				(width 0.1)
				(type default)
			)
			(layer "B.Fab")
		)
		(fp_line
			(start 0.12065 -0.305054)
			(end 0.12065 -0.2794)
			(stroke
				(width 0.1)
				(type default)
			)
			(layer "B.Fab")
		)
		(fp_line
			(start -0.120396 0.3048)
			(end -0.120396 0.2794)
			(stroke
				(width 0.1)
				(type default)
			)
			(layer "B.Fab")
		)
		(fp_line
			(start -0.120396 0.2794)
			(end 0.12065 0.2794)
			(stroke
				(width 0.1)
				(type default)
			)
			(layer "B.Fab")
		)
		(fp_line
			(start -0.12065 -0.2794)
			(end -0.12065 -0.3048)
			(stroke
				(width 0.1)
				(type default)
			)
			(layer "B.Fab")
		)
		(fp_line
			(start -0.12065 -0.3048)
			(end -0.67945 -0.3048)
			(stroke
				(width 0.1)
				(type default)
			)
			(layer "B.Fab")
		)
		(fp_line
			(start -0.67945 0.3048)
			(end -0.120396 0.3048)
			(stroke
				(width 0.1)
				(type default)
			)
			(layer "B.Fab")
		)
		(fp_line
			(start -0.67945 -0.3048)
			(end -0.67945 0.3048)
			(stroke
				(width 0.1)
				(type default)
			)
			(layer "B.Fab")
		)
		(pad "1" smd circle
			(at 0.40005 0)
			(size 0 0)
			(layers "B.Cu" "B.Mask" "B.Paste")
			(net "UART_PEX0_CLI_BUF_TX")
		)
		(pad "2" smd circle
			(at -0.40005 0)
			(size 0 0)
			(layers "B.Cu" "B.Mask" "B.Paste")
			(net "P3V3_AUX")
		)
	)
	(footprint ""
		(layer "B.Cu")
		(at 301.204122 -117.723666)
		(property "Reference" "C421"
			(at 0 0 0)
			(layer "B.SilkS")
			(hide yes)
			(effects
				(font
					(size 1.27 1.27)
				)
				(justify mirror)
			)
		)
		(property "Value" ""
			(at 0 0 0)
			(layer "B.Fab")
			(effects
				(font
					(size 1.27 1.27)
				)
				(justify mirror)
			)
		)
		(duplicate_pad_numbers_are_jumpers no)
		(fp_line
			(start -0.7874 -0.4064)
			(end -0.7874 0.4064)
			(stroke
				(width 0.1524)
				(type default)
			)
			(layer "B.SilkS")
		)
		(fp_line
			(start -0.7874 0.4064)
			(end 0.7874 0.4064)
			(stroke
				(width 0.1524)
				(type default)
			)
			(layer "B.SilkS")
		)
		(fp_line
			(start 0.7874 -0.4064)
			(end -0.7874 -0.4064)
			(stroke
				(width 0.1524)
				(type default)
			)
			(layer "B.SilkS")
		)
		(fp_line
			(start 0.7874 0.4064)
			(end 0.7874 -0.4064)
			(stroke
				(width 0.1524)
				(type default)
			)
			(layer "B.SilkS")
		)
		(fp_line
			(start -0.67945 -0.3048)
			(end -0.67945 0.3048)
			(stroke
				(width 0.1)
				(type default)
			)
			(layer "B.Fab")
		)
		(fp_line
			(start -0.67945 0.3048)
			(end -0.120396 0.3048)
			(stroke
				(width 0.1)
				(type default)
			)
			(layer "B.Fab")
		)
		(fp_line
			(start -0.12065 -0.3048)
			(end -0.67945 -0.3048)
			(stroke
				(width 0.1)
				(type default)
			)
			(layer "B.Fab")
		)
		(fp_line
			(start -0.12065 -0.2794)
			(end -0.12065 -0.3048)
			(stroke
				(width 0.1)
				(type default)
			)
			(layer "B.Fab")
		)
		(fp_line
			(start -0.120396 0.2794)
			(end 0.12065 0.2794)
			(stroke
				(width 0.1)
				(type default)
			)
			(layer "B.Fab")
		)
		(fp_line
			(start -0.120396 0.3048)
			(end -0.120396 0.2794)
			(stroke
				(width 0.1)
				(type default)
			)
			(layer "B.Fab")
		)
		(fp_line
			(start 0.12065 -0.305054)
			(end 0.12065 -0.2794)
			(stroke
				(width 0.1)
				(type default)
			)
			(layer "B.Fab")
		)
		(fp_line
			(start 0.12065 -0.2794)
			(end -0.12065 -0.2794)
			(stroke
				(width 0.1)
				(type default)
			)
			(layer "B.Fab")
		)
		(fp_line
			(start 0.12065 0.2794)
			(end 0.12065 0.3048)
			(stroke
				(width 0.1)
				(type default)
			)
			(layer "B.Fab")
		)
		(fp_line
			(start 0.12065 0.3048)
			(end 0.67945 0.3048)
			(stroke
				(width 0.1)
				(type default)
			)
			(layer "B.Fab")
		)
		(fp_line
			(start 0.67945 -0.305054)
			(end 0.12065 -0.305054)
			(stroke
				(width 0.1)
				(type default)
			)
			(layer "B.Fab")
		)
		(fp_line
			(start 0.67945 0.3048)
			(end 0.67945 -0.305054)
			(stroke
				(width 0.1)
				(type default)
			)
			(layer "B.Fab")
		)
		(pad "1" smd circle
			(at 0.40005 0 180)
			(size 0 0)
			(layers "B.Cu" "B.Mask" "B.Paste")
			(net "P3V3_AUX")
		)
		(pad "2" smd circle
			(at -0.40005 0 180)
			(size 0 0)
			(layers "B.Cu" "B.Mask" "B.Paste")
			(net "GND")
		)
	)
	(footprint ""
		(layer "B.Cu")
		(at 301.824898 -305.608228 -90)
		(property "Reference" "C3346"
			(at 0 0 90)
			(layer "B.SilkS")
			(hide yes)
			(effects
				(font
					(size 1.27 1.27)
				)
				(justify mirror)
			)
		)
		(property "Value" ""
			(at 0 0 90)
			(layer "B.Fab")
			(effects
				(font
					(size 1.27 1.27)
				)
				(justify mirror)
			)
		)
		(duplicate_pad_numbers_are_jumpers no)
		(fp_line
			(start -0.299974 0.150114)
			(end 0.299974 0.150114)
			(stroke
				(width 0.1)
				(type default)
			)
			(layer "B.Fab")
		)
		(fp_line
			(start 0.299974 0.150114)
			(end 0.299974 -0.150114)
			(stroke
				(width 0.1)
				(type default)
			)
			(layer "B.Fab")
		)
		(fp_line
			(start -0.299974 -0.150114)
			(end -0.299974 0.150114)
			(stroke
				(width 0.1)
				(type default)
			)
			(layer "B.Fab")
		)
		(fp_line
			(start 0.299974 -0.150114)
			(end -0.299974 -0.150114)
			(stroke
				(width 0.1)
				(type default)
			)
			(layer "B.Fab")
		)
		(pad "1" smd rect
			(at 0.2667 0 90)
			(size 0.3048 0.381)
			(layers "B.Cu" "B.Mask" "B.Paste")
			(net "P1V8_VDDA_PEX2")
		)
		(pad "2" smd rect
			(at -0.2667 0 90)
			(size 0.3048 0.381)
			(layers "B.Cu" "B.Mask" "B.Paste")
			(net "GND")
		)
	)
	(footprint ""
		(layer "B.Cu")
		(at 194.601846 -295.422066 180)
		(property "Reference" "C3082"
			(at 0 0 0)
			(layer "B.SilkS")
			(hide yes)
			(effects
				(font
					(size 1.27 1.27)
				)
				(justify mirror)
			)
		)
		(property "Value" ""
			(at 0 0 0)
			(layer "B.Fab")
			(effects
				(font
					(size 1.27 1.27)
				)
				(justify mirror)
			)
		)
		(duplicate_pad_numbers_are_jumpers no)
		(fp_line
			(start 1.2954 0.5842)
			(end 1.2954 -0.5842)
			(stroke
				(width 0.1524)
				(type default)
			)
			(layer "B.SilkS")
		)
		(fp_line
			(start 1.2954 -0.5842)
			(end -1.2954 -0.5842)
			(stroke
				(width 0.1524)
				(type default)
			)
			(layer "B.SilkS")
		)
		(fp_line
			(start -1.2954 0.5842)
			(end 1.2954 0.5842)
			(stroke
				(width 0.1524)
				(type default)
			)
			(layer "B.SilkS")
		)
		(fp_line
			(start -1.2954 -0.5842)
			(end -1.2954 0.5842)
			(stroke
				(width 0.1524)
				(type default)
			)
			(layer "B.SilkS")
		)
		(fp_line
			(start 1.1938 0.4064)
			(end 1.1938 -0.4064)
			(stroke
				(width 0.1)
				(type default)
			)
			(layer "B.Fab")
		)
		(fp_line
			(start 1.1938 -0.4064)
			(end 0.8636 -0.4064)
			(stroke
				(width 0.1)
				(type default)
			)
			(layer "B.Fab")
		)
		(fp_line
			(start 0.8636 0.4572)
			(end 0.8636 0.4064)
			(stroke
				(width 0.1)
				(type default)
			)
			(layer "B.Fab")
		)
		(fp_line
			(start 0.8636 0.4064)
			(end 1.1938 0.4064)
			(stroke
				(width 0.1)
				(type default)
			)
			(layer "B.Fab")
		)
		(fp_line
			(start 0.8636 -0.4064)
			(end 0.8636 -0.4572)
			(stroke
				(width 0.1)
				(type default)
			)
			(layer "B.Fab")
		)
		(fp_line
			(start 0.8636 -0.4572)
			(end -0.8636 -0.4572)
			(stroke
				(width 0.1)
				(type default)
			)
			(layer "B.Fab")
		)
		(fp_line
			(start -0.8636 0.4572)
			(end 0.8636 0.4572)
			(stroke
				(width 0.1)
				(type default)
			)
			(layer "B.Fab")
		)
		(fp_line
			(start -0.8636 0.4064)
			(end -0.8636 0.4572)
			(stroke
				(width 0.1)
				(type default)
			)
			(layer "B.Fab")
		)
		(fp_line
			(start -0.8636 -0.4064)
			(end -1.1938 -0.4064)
			(stroke
				(width 0.1)
				(type default)
			)
			(layer "B.Fab")
		)
		(fp_line
			(start -0.8636 -0.4572)
			(end -0.8636 -0.4064)
			(stroke
				(width 0.1)
				(type default)
			)
			(layer "B.Fab")
		)
		(fp_line
			(start -1.1938 0.4064)
			(end -0.8636 0.4064)
			(stroke
				(width 0.1)
				(type default)
			)
			(layer "B.Fab")
		)
		(fp_line
			(start -1.1938 -0.4064)
			(end -1.1938 0.4064)
			(stroke
				(width 0.1)
				(type default)
			)
			(layer "B.Fab")
		)
		(pad "1" smd rect
			(at 0.7366 0 90)
			(size 0.7112 0.8128)
			(layers "B.Cu" "B.Mask" "B.Paste")
			(net "P1V25_PEX1")
		)
		(pad "2" smd rect
			(at -0.7366 0 90)
			(size 0.7112 0.8128)
			(layers "B.Cu" "B.Mask" "B.Paste")
			(net "GND")
		)
	)
	(footprint ""
		(layer "B.Cu")
		(at 256.351532 -82.140044 180)
		(property "Reference" "C2639"
			(at 0 0 0)
			(layer "B.SilkS")
			(hide yes)
			(effects
				(font
					(size 1.27 1.27)
				)
				(justify mirror)
			)
		)
		(property "Value" ""
			(at 0 0 0)
			(layer "B.Fab")
			(effects
				(font
					(size 1.27 1.27)
				)
				(justify mirror)
			)
		)
		(duplicate_pad_numbers_are_jumpers no)
		(fp_line
			(start 0.7874 0.4064)
			(end 0.7874 -0.4064)
			(stroke
				(width 0.1524)
				(type default)
			)
			(layer "B.SilkS")
		)
		(fp_line
			(start 0.7874 -0.4064)
			(end -0.7874 -0.4064)
			(stroke
				(width 0.1524)
				(type default)
			)
			(layer "B.SilkS")
		)
		(fp_line
			(start -0.7874 0.4064)
			(end 0.7874 0.4064)
			(stroke
				(width 0.1524)
				(type default)
			)
			(layer "B.SilkS")
		)
		(fp_line
			(start -0.7874 -0.4064)
			(end -0.7874 0.4064)
			(stroke
				(width 0.1524)
				(type default)
			)
			(layer "B.SilkS")
		)
		(fp_line
			(start 0.67945 0.3048)
			(end 0.67945 -0.305054)
			(stroke
				(width 0.1)
				(type default)
			)
			(layer "B.Fab")
		)
		(fp_line
			(start 0.67945 -0.305054)
			(end 0.12065 -0.305054)
			(stroke
				(width 0.1)
				(type default)
			)
			(layer "B.Fab")
		)
		(fp_line
			(start 0.12065 0.3048)
			(end 0.67945 0.3048)
			(stroke
				(width 0.1)
				(type default)
			)
			(layer "B.Fab")
		)
		(fp_line
			(start 0.12065 0.2794)
			(end 0.12065 0.3048)
			(stroke
				(width 0.1)
				(type default)
			)
			(layer "B.Fab")
		)
		(fp_line
			(start 0.12065 -0.2794)
			(end -0.12065 -0.2794)
			(stroke
				(width 0.1)
				(type default)
			)
			(layer "B.Fab")
		)
		(fp_line
			(start 0.12065 -0.305054)
			(end 0.12065 -0.2794)
			(stroke
				(width 0.1)
				(type default)
			)
			(layer "B.Fab")
		)
		(fp_line
			(start -0.120396 0.3048)
			(end -0.120396 0.2794)
			(stroke
				(width 0.1)
				(type default)
			)
			(layer "B.Fab")
		)
		(fp_line
			(start -0.120396 0.2794)
			(end 0.12065 0.2794)
			(stroke
				(width 0.1)
				(type default)
			)
			(layer "B.Fab")
		)
		(fp_line
			(start -0.12065 -0.2794)
			(end -0.12065 -0.3048)
			(stroke
				(width 0.1)
				(type default)
			)
			(layer "B.Fab")
		)
		(fp_line
			(start -0.12065 -0.3048)
			(end -0.67945 -0.3048)
			(stroke
				(width 0.1)
				(type default)
			)
			(layer "B.Fab")
		)
		(fp_line
			(start -0.67945 0.3048)
			(end -0.120396 0.3048)
			(stroke
				(width 0.1)
				(type default)
			)
			(layer "B.Fab")
		)
		(fp_line
			(start -0.67945 -0.3048)
			(end -0.67945 0.3048)
			(stroke
				(width 0.1)
				(type default)
			)
			(layer "B.Fab")
		)
		(pad "1" smd circle
			(at 0.40005 0)
			(size 0 0)
			(layers "B.Cu" "B.Mask" "B.Paste")
			(net "P3V3_CLK_GEN_VDDXTAL_CK440")
		)
		(pad "2" smd circle
			(at -0.40005 0)
			(size 0 0)
			(layers "B.Cu" "B.Mask" "B.Paste")
			(net "GND")
		)
	)
	(footprint ""
		(layer "B.Cu")
		(at 416.972242 -113.437924)
		(property "Reference" "R367"
			(at 0 0 0)
			(layer "B.SilkS")
			(hide yes)
			(effects
				(font
					(size 1.27 1.27)
				)
				(justify mirror)
			)
		)
		(property "Value" ""
			(at 0 0 0)
			(layer "B.Fab")
			(effects
				(font
					(size 1.27 1.27)
				)
				(justify mirror)
			)
		)
		(duplicate_pad_numbers_are_jumpers no)
		(fp_line
			(start -0.7874 -0.4064)
			(end -0.7874 0.4064)
			(stroke
				(width 0.1524)
				(type default)
			)
			(layer "B.SilkS")
		)
		(fp_line
			(start -0.7874 0.4064)
			(end 0.7874 0.4064)
			(stroke
				(width 0.1524)
				(type default)
			)
			(layer "B.SilkS")
		)
		(fp_line
			(start 0.7874 -0.4064)
			(end -0.7874 -0.4064)
			(stroke
				(width 0.1524)
				(type default)
			)
			(layer "B.SilkS")
		)
		(fp_line
			(start 0.7874 0.4064)
			(end 0.7874 -0.4064)
			(stroke
				(width 0.1524)
				(type default)
			)
			(layer "B.SilkS")
		)
		(fp_line
			(start -0.67945 -0.3048)
			(end -0.67945 0.3048)
			(stroke
				(width 0.1)
				(type default)
			)
			(layer "B.Fab")
		)
		(fp_line
			(start -0.67945 0.3048)
			(end -0.120396 0.3048)
			(stroke
				(width 0.1)
				(type default)
			)
			(layer "B.Fab")
		)
		(fp_line
			(start -0.12065 -0.3048)
			(end -0.67945 -0.3048)
			(stroke
				(width 0.1)
				(type default)
			)
			(layer "B.Fab")
		)
		(fp_line
			(start -0.12065 -0.2794)
			(end -0.12065 -0.3048)
			(stroke
				(width 0.1)
				(type default)
			)
			(layer "B.Fab")
		)
		(fp_line
			(start -0.120396 0.2794)
			(end 0.12065 0.2794)
			(stroke
				(width 0.1)
				(type default)
			)
			(layer "B.Fab")
		)
		(fp_line
			(start -0.120396 0.3048)
			(end -0.120396 0.2794)
			(stroke
				(width 0.1)
				(type default)
			)
			(layer "B.Fab")
		)
		(fp_line
			(start 0.12065 -0.305054)
			(end 0.12065 -0.2794)
			(stroke
				(width 0.1)
				(type default)
			)
			(layer "B.Fab")
		)
		(fp_line
			(start 0.12065 -0.2794)
			(end -0.12065 -0.2794)
			(stroke
				(width 0.1)
				(type default)
			)
			(layer "B.Fab")
		)
		(fp_line
			(start 0.12065 0.2794)
			(end 0.12065 0.3048)
			(stroke
				(width 0.1)
				(type default)
			)
			(layer "B.Fab")
		)
		(fp_line
			(start 0.12065 0.3048)
			(end 0.67945 0.3048)
			(stroke
				(width 0.1)
				(type default)
			)
			(layer "B.Fab")
		)
		(fp_line
			(start 0.67945 -0.305054)
			(end 0.12065 -0.305054)
			(stroke
				(width 0.1)
				(type default)
			)
			(layer "B.Fab")
		)
		(fp_line
			(start 0.67945 0.3048)
			(end 0.67945 -0.305054)
			(stroke
				(width 0.1)
				(type default)
			)
			(layer "B.Fab")
		)
		(pad "1" smd circle
			(at 0.40005 0 180)
			(size 0 0)
			(layers "B.Cu" "B.Mask" "B.Paste")
			(net "P3V3_NIC7")
		)
		(pad "2" smd circle
			(at -0.40005 0 180)
			(size 0 0)
			(layers "B.Cu" "B.Mask" "B.Paste")
			(net "SMB_NIC7_LS_SDA")
		)
	)
	(footprint ""
		(layer "B.Cu")
		(at 456.818238 -266.996672 180)
		(property "Reference" "R6139"
			(at 0 0 0)
			(layer "B.SilkS")
			(hide yes)
			(effects
				(font
					(size 1.27 1.27)
				)
				(justify mirror)
			)
		)
		(property "Value" ""
			(at 0 0 0)
			(layer "B.Fab")
			(effects
				(font
					(size 1.27 1.27)
				)
				(justify mirror)
			)
		)
		(duplicate_pad_numbers_are_jumpers no)
		(fp_line
			(start 2.576322 1.1303)
			(end 2.576322 -1.1303)
			(stroke
				(width 0.1524)
				(type default)
			)
			(layer "B.SilkS")
		)
		(fp_line
			(start 2.576322 -1.1303)
			(end -2.576322 -1.1303)
			(stroke
				(width 0.1524)
				(type default)
			)
			(layer "B.SilkS")
		)
		(fp_line
			(start -2.576322 1.1303)
			(end 2.576322 1.1303)
			(stroke
				(width 0.1524)
				(type default)
			)
			(layer "B.SilkS")
		)
		(fp_line
			(start -2.576322 -1.1303)
			(end -2.576322 1.1303)
			(stroke
				(width 0.1524)
				(type default)
			)
			(layer "B.SilkS")
		)
		(fp_line
			(start 1.649984 0.899922)
			(end -1.649984 0.899922)
			(stroke
				(width 0.1)
				(type default)
			)
			(layer "B.Fab")
		)
		(fp_line
			(start 1.649984 -0.899922)
			(end 1.649984 0.899922)
			(stroke
				(width 0.1)
				(type default)
			)
			(layer "B.Fab")
		)
		(fp_line
			(start -1.649984 0.899922)
			(end -1.649984 -0.899922)
			(stroke
				(width 0.1)
				(type default)
			)
			(layer "B.Fab")
		)
		(fp_line
			(start -1.649984 -0.899922)
			(end 1.649984 -0.899922)
			(stroke
				(width 0.1)
				(type default)
			)
			(layer "B.Fab")
		)
		(pad "1A" smd rect
			(at 1.700022 0)
			(size 1.4986 2.0066)
			(layers "B.Cu" "B.Mask" "B.Paste")
			(net "P1V25_PEX3")
		)
		(pad "1B" smd rect
			(at 1.077722 0)
			(size 0.254 0.508)
			(layers "B.Cu" "B.Mask" "B.Paste")
			(net "P1V25_PEX3")
		)
		(pad "2A" smd rect
			(at -1.700022 0)
			(size 1.4986 2.0066)
			(layers "B.Cu" "B.Mask" "B.Paste")
			(net "P1V25_SERDES_VDDPLL_PEX3")
		)
		(pad "2B" smd rect
			(at -1.077722 0)
			(size 0.254 0.508)
			(layers "B.Cu" "B.Mask" "B.Paste")
			(net "P1V25_SERDES_VDDPLL_PEX3")
		)
	)
)
